# S9S_MB_2U (Grand Teton) — schematic netlist excerpt (pin names and nets, part order shuffled) for the footprints in the layout excerpt that follows; sources: Cadence DE-HDL packaged netlist, KiCad conversion of 03242023_DA0F0TMBIJ0_F0T_Motherboard_J_brd_V01_OCP.brd

R4457  Q_RES  10K 1% EMPTY  pkg 0402LF  page 196 : A = P3V3_AUX ; B = USB_HUB_2_OVCUR2
H122  HOLE  EMPTY  pkg TH  page 311 : \1\ = NC
PC234  Q_CAP  100NF 50V 10% X7R  pkg C0402  page 270 : A = SW_PVCCIN_CPU0_BOOT8_R ; B = SW_PVCCIN_CPU0_BOOTR8

(kicad_pcb
	(version 20260206)
	(generator "pcbnew")
	(generator_version "10.0")
	(general
		(thickness 1.6)
		(legacy_teardrops no)
	)
	(paper "A4")
	(title_block
		(title "03242023_DA0F0TMBIJ0_F0T_Motherboard_J_brd_V01_OCP.brd")
		(comment 1 "Grand Teton / footprints 1561-1563 of 6105")
	)
	(layers
		(0 "F.Cu" signal "TOP")
		(4 "In1.Cu" signal "GND")
		(6 "In2.Cu" signal "IN1")
		(8 "In3.Cu" signal "GND1")
		(10 "In4.Cu" signal "IN2")
		(12 "In5.Cu" signal "GND2")
		(14 "In6.Cu" signal "IN3")
		(16 "In7.Cu" signal "GND3")
		(18 "In8.Cu" signal "VCC")
		(20 "In9.Cu" signal "VCC1")
		(22 "In10.Cu" signal "GND4")
		(24 "In11.Cu" signal "IN4")
		(26 "In12.Cu" signal "GND5")
		(28 "In13.Cu" signal "IN5")
		(30 "In14.Cu" signal "GND6")
		(32 "In15.Cu" signal "IN6")
		(34 "In16.Cu" signal "GND7")
		(2 "B.Cu" signal "BOTTOM")
		(9 "F.Adhes" user "F.Adhesive")
		(11 "B.Adhes" user "B.Adhesive")
		(13 "F.Paste" user "Package Geometry/Pastemask Top")
		(15 "B.Paste" user "Package Geometry/Pastemask Bottom")
		(5 "F.SilkS" user "Ref Des/Silkscreen Top")
		(7 "B.SilkS" user "Ref Des/Silkscreen Bottom")
		(1 "F.Mask" user "Board Geometry/Soldermask Top")
		(3 "B.Mask" user "Board Geometry/Soldermask Bottom")
		(17 "Dwgs.User" user "User.Drawings")
		(19 "Cmts.User" user "User.Comments")
		(21 "Eco1.User" user "User.Eco1")
		(23 "Eco2.User" user "User.Eco2")
		(25 "Edge.Cuts" user "Board Geometry/Outline")
		(27 "Margin" user)
		(31 "F.CrtYd" user "Package Geometry/Place Bound Top")
		(29 "B.CrtYd" user "Package Geometry/Place Bound Bottom")
		(35 "F.Fab" user "Ref Des/Assembly Top")
		(33 "B.Fab" user "Ref Des/Assembly Bottom")
	)
	(footprint ""
		(layer "F.Cu")
		(at 387.526022 -347.520514 -90)
		(property "Reference" "PC234"
			(at 0 0 270)
			(layer "F.SilkS")
			(hide yes)
			(effects
				(font
					(size 1.27 1.27)
				)
			)
		)
		(property "Value" ""
			(at 0 0 270)
			(layer "F.Fab")
			(effects
				(font
					(size 1.27 1.27)
				)
			)
		)
		(duplicate_pad_numbers_are_jumpers no)
		(fp_line
			(start -0.7874 0.4064)
			(end -0.7874 -0.4064)
			(stroke
				(width 0.1524)
				(type default)
			)
			(layer "F.SilkS")
		)
		(fp_line
			(start 0.7874 0.4064)
			(end -0.7874 0.4064)
			(stroke
				(width 0.1524)
				(type default)
			)
			(layer "F.SilkS")
		)
		(fp_line
			(start -0.7874 -0.4064)
			(end 0.7874 -0.4064)
			(stroke
				(width 0.1524)
				(type default)
			)
			(layer "F.SilkS")
		)
		(fp_line
			(start 0.7874 -0.4064)
			(end 0.7874 0.4064)
			(stroke
				(width 0.1524)
				(type default)
			)
			(layer "F.SilkS")
		)
		(fp_line
			(start -0.67945 0.3048)
			(end -0.67945 -0.305054)
			(stroke
				(width 0.1)
				(type default)
			)
			(layer "F.Fab")
		)
		(fp_line
			(start -0.12065 0.3048)
			(end -0.67945 0.3048)
			(stroke
				(width 0.1)
				(type default)
			)
			(layer "F.Fab")
		)
		(fp_line
			(start 0.120396 0.3048)
			(end 0.120396 0.2794)
			(stroke
				(width 0.1)
				(type default)
			)
			(layer "F.Fab")
		)
		(fp_line
			(start 0.67945 0.3048)
			(end 0.120396 0.3048)
			(stroke
				(width 0.1)
				(type default)
			)
			(layer "F.Fab")
		)
		(fp_line
			(start -0.12065 0.2794)
			(end -0.12065 0.3048)
			(stroke
				(width 0.1)
				(type default)
			)
			(layer "F.Fab")
		)
		(fp_line
			(start 0.120396 0.2794)
			(end -0.12065 0.2794)
			(stroke
				(width 0.1)
				(type default)
			)
			(layer "F.Fab")
		)
		(fp_line
			(start -0.12065 -0.2794)
			(end 0.12065 -0.2794)
			(stroke
				(width 0.1)
				(type default)
			)
			(layer "F.Fab")
		)
		(fp_line
			(start 0.12065 -0.2794)
			(end 0.12065 -0.3048)
			(stroke
				(width 0.1)
				(type default)
			)
			(layer "F.Fab")
		)
		(fp_line
			(start 0.12065 -0.3048)
			(end 0.67945 -0.3048)
			(stroke
				(width 0.1)
				(type default)
			)
			(layer "F.Fab")
		)
		(fp_line
			(start 0.67945 -0.3048)
			(end 0.67945 0.3048)
			(stroke
				(width 0.1)
				(type default)
			)
			(layer "F.Fab")
		)
		(fp_line
			(start -0.67945 -0.305054)
			(end -0.12065 -0.305054)
			(stroke
				(width 0.1)
				(type default)
			)
			(layer "F.Fab")
		)
		(fp_line
			(start -0.12065 -0.305054)
			(end -0.12065 -0.2794)
			(stroke
				(width 0.1)
				(type default)
			)
			(layer "F.Fab")
		)
		(pad "1" smd circle
			(at -0.40005 0 270)
			(size 0 0)
			(layers "F.Cu" "F.Mask" "F.Paste")
			(net "SW_PVCCIN_CPU0_BOOT8_R")
		)
		(pad "2" smd circle
			(at 0.40005 0 270)
			(size 0 0)
			(layers "F.Cu" "F.Mask" "F.Paste")
			(net "SW_PVCCIN_CPU0_BOOTR8")
		)
	)
	(footprint ""
		(layer "F.Cu")
		(at 164.247576 -38.067234 180)
		(property "Reference" "R4457"
			(at 0 0 180)
			(layer "F.SilkS")
			(hide yes)
			(effects
				(font
					(size 1.27 1.27)
				)
			)
		)
		(property "Value" ""
			(at 0 0 180)
			(layer "F.Fab")
			(effects
				(font
					(size 1.27 1.27)
				)
			)
		)
		(duplicate_pad_numbers_are_jumpers no)
		(fp_line
			(start 0.7874 0.4064)
			(end -0.7874 0.4064)
			(stroke
				(width 0.1524)
				(type default)
			)
			(layer "F.SilkS")
		)
		(fp_line
			(start 0.7874 -0.4064)
			(end 0.7874 0.4064)
			(stroke
				(width 0.1524)
				(type default)
			)
			(layer "F.SilkS")
		)
		(fp_line
			(start -0.7874 0.4064)
			(end -0.7874 -0.4064)
			(stroke
				(width 0.1524)
				(type default)
			)
			(layer "F.SilkS")
		)
		(fp_line
			(start -0.7874 -0.4064)
			(end 0.7874 -0.4064)
			(stroke
				(width 0.1524)
				(type default)
			)
			(layer "F.SilkS")
		)
		(fp_line
			(start 0.67945 0.3048)
			(end 0.120396 0.3048)
			(stroke
				(width 0.1)
				(type default)
			)
			(layer "F.Fab")
		)
		(fp_line
			(start 0.67945 -0.3048)
			(end 0.67945 0.3048)
			(stroke
				(width 0.1)
				(type default)
			)
			(layer "F.Fab")
		)
		(fp_line
			(start 0.12065 -0.2794)
			(end 0.12065 -0.3048)
			(stroke
				(width 0.1)
				(type default)
			)
			(layer "F.Fab")
		)
		(fp_line
			(start 0.12065 -0.3048)
			(end 0.67945 -0.3048)
			(stroke
				(width 0.1)
				(type default)
			)
			(layer "F.Fab")
		)
		(fp_line
			(start 0.120396 0.3048)
			(end 0.120396 0.2794)
			(stroke
				(width 0.1)
				(type default)
			)
			(layer "F.Fab")
		)
		(fp_line
			(start 0.120396 0.2794)
			(end -0.12065 0.2794)
			(stroke
				(width 0.1)
				(type default)
			)
			(layer "F.Fab")
		)
		(fp_line
			(start -0.12065 0.3048)
			(end -0.67945 0.3048)
			(stroke
				(width 0.1)
				(type default)
			)
			(layer "F.Fab")
		)
		(fp_line
			(start -0.12065 0.2794)
			(end -0.12065 0.3048)
			(stroke
				(width 0.1)
				(type default)
			)
			(layer "F.Fab")
		)
		(fp_line
			(start -0.12065 -0.2794)
			(end 0.12065 -0.2794)
			(stroke
				(width 0.1)
				(type default)
			)
			(layer "F.Fab")
		)
		(fp_line
			(start -0.12065 -0.305054)
			(end -0.12065 -0.2794)
			(stroke
				(width 0.1)
				(type default)
			)
			(layer "F.Fab")
		)
		(fp_line
			(start -0.67945 0.3048)
			(end -0.67945 -0.305054)
			(stroke
				(width 0.1)
				(type default)
			)
			(layer "F.Fab")
		)
		(fp_line
			(start -0.67945 -0.305054)
			(end -0.12065 -0.305054)
			(stroke
				(width 0.1)
				(type default)
			)
			(layer "F.Fab")
		)
		(pad "1" smd circle
			(at -0.40005 0 180)
			(size 0 0)
			(layers "F.Cu" "F.Mask" "F.Paste")
			(net "P3V3_AUX")
		)
		(pad "2" smd circle
			(at 0.40005 0 180)
			(size 0 0)
			(layers "F.Cu" "F.Mask" "F.Paste")
			(net "USB_HUB_2_OVCUR2")
		)
	)
	(footprint ""
		(layer "F.Cu")
		(at 277.894796 -153.76652)
		(property "Reference" "H122"
			(at -2.5527 -8.20293 0)
			(unlocked yes)
			(layer "F.SilkS")
			(effects
				(font
					(size 0.7874 0.5842)
					(thickness 0.1524)
				)
				(justify left)
			)
		)
		(property "Value" ""
			(at 0 0 0)
			(layer "F.Fab")
			(effects
				(font
					(size 1.27 1.27)
				)
			)
		)
		(duplicate_pad_numbers_are_jumpers no)
		(fp_circle
			(center 0 0)
			(end 5.8166 0)
			(stroke
				(width 0.1524)
				(type default)
			)
			(fill no)
			(layer "F.SilkS")
		)
		(fp_circle
			(center 0 0)
			(end 5.8166 0)
			(stroke
				(width 0.1524)
				(type default)
			)
			(fill no)
			(layer "B.SilkS")
		)
		(fp_circle
			(center 0 0)
			(end 5.8166 0)
			(stroke
				(width 0.1)
				(type default)
			)
			(fill no)
			(layer "B.Fab")
		)
		(fp_circle
			(center 0 0)
			(end 5.8166 0)
			(stroke
				(width 0.1)
				(type default)
			)
			(fill no)
			(layer "F.Fab")
		)
		(pad "" np_thru_hole circle
			(at 0 0)
			(size 10.0076 10.0076)
			(drill 10.0076)
			(layers "*.Cu" "*.Mask")
			(clearance 0.381)
			(thermal_gap 0.381)
		)
	)
)
